(kicad_pcb
	(version 20241229)
	(generator "pcbnew")
	(generator_version "9.0")
	(general
		(thickness 1.62)
		(legacy_teardrops no)
	)
	(paper "A3")
	(title_block
		(title "COM Express 7 Baseboard")
		(date "2025-02-04")
		(rev "1.1.2")
		(company "Antmicro Ltd")
		(comment 1 "www.antmicro.com")
		(comment 9 "footprints 359-361 of 802")
	)
	(layers
		(0 "F.Cu" signal)
		(4 "In1.Cu" signal)
		(6 "In2.Cu" signal)
		(8 "In3.Cu" signal)
		(10 "In4.Cu" signal)
		(12 "In5.Cu" signal)
		(14 "In6.Cu" signal)
		(2 "B.Cu" signal)
		(9 "F.Adhes" user "F.Adhesive")
		(11 "B.Adhes" user "B.Adhesive")
		(13 "F.Paste" user)
		(15 "B.Paste" user)
		(5 "F.SilkS" user "F.Silkscreen")
		(7 "B.SilkS" user "B.Silkscreen")
		(1 "F.Mask" user)
		(3 "B.Mask" user)
		(17 "Dwgs.User" user "User.Drawings")
		(19 "Cmts.User" user "User.Comments")
		(21 "Eco1.User" user "User.Eco1")
		(23 "Eco2.User" user "User.Eco2")
		(25 "Edge.Cuts" user)
		(27 "Margin" user)
		(31 "F.CrtYd" user "F.Courtyard")
		(29 "B.CrtYd" user "B.Courtyard")
		(35 "F.Fab" user)
		(33 "B.Fab" user)
	)
	(footprint "antmicro-footprints:Spacer_Drill3.7mm_H2.5mm_9774025151R"
		(layer "F.Cu")
		(at 120.0745 80.3095 -90)
		(descr "Spacer M=3 h=2.5mm fi=5.1mm")
		(property "Reference" "H3"
			(at -0.1095 -4.1255 90)
			(layer "F.SilkS")
			(hide yes)
			(effects
				(font
					(size 0.7 0.7)
					(thickness 0.15)
				)
				(justify right bottom)
			)
		)
		(property "Value" "Spacer_Drill3.7mm_H2.5mm_9774025151R"
			(at 0 4 90)
			(layer "F.Fab")
			(effects
				(font
					(size 0.7 0.7)
					(thickness 0.15)
				)
				(justify right bottom)
			)
		)
		(property "Datasheet" "https://www.we-online.com/components/products/datasheet/9774025151R.pdf"
			(at 0 0 270)
			(layer "F.Fab")
			(hide yes)
			(effects
				(font
					(size 1.27 1.27)
					(thickness 0.15)
				)
			)
		)
		(property "Author" "Antmicro"
			(at 39.765 200.384 0)
			(layer "F.Fab")
			(hide yes)
			(effects
				(font
					(size 1 1)
					(thickness 0.15)
				)
			)
		)
		(property "License" "Apache-2.0"
			(at 39.765 200.384 0)
			(layer "F.Fab")
			(hide yes)
			(effects
				(font
					(size 1 1)
					(thickness 0.15)
				)
			)
		)
		(property "MPN" "9774025151R"
			(at 39.765 200.384 0)
			(layer "F.Fab")
			(hide yes)
			(effects
				(font
					(size 1 1)
					(thickness 0.15)
				)
			)
		)
		(property "Manufacturer" "Würth Elektronik"
			(at 39.765 200.384 0)
			(layer "F.Fab")
			(hide yes)
			(effects
				(font
					(size 1 1)
					(thickness 0.15)
				)
			)
		)
		(property "Public" "False"
			(at 39.765 200.384 0)
			(layer "F.Fab")
			(hide yes)
			(effects
				(font
					(size 1 1)
					(thickness 0.15)
				)
			)
		)
		(sheetname "M.2 key E")
		(sheetfile "m2keye.kicad_sch")
		(solder_paste_margin_ratio -1)
		(attr smd)
		(fp_circle
			(center 0 0)
			(end 3.05 0)
			(stroke
				(width 0.05)
				(type solid)
			)
			(fill no)
			(layer "F.CrtYd")
		)
		(fp_circle
			(center 0 0)
			(end 2.6 0)
			(stroke
				(width 0.15)
				(type solid)
			)
			(fill no)
			(layer "F.Fab")
		)
		(pad "" smd custom
			(at -1.7 -1.7 270)
			(size 0.62 0.62)
			(layers "F.Paste")
			(thermal_bridge_angle 90)
			(options
				(clearance outline)
				(anchor circle)
			)
			(primitives
				(gr_arc
					(start -0.250195 1.279127)
					(mid 0.285453 0.294389)
					(end 1.266786 -0.24747)
					(width 0.2)
				)
				(gr_arc
					(start -0.34334 1.279127)
					(mid 0.218448 0.232561)
					(end 1.259603 -0.339191)
					(width 0.2)
				)
				(gr_arc
					(start -0.436309 1.279127)
					(mid 0.152481 0.169693)
					(end 1.255279 -0.431435)
					(width 0.2)
				)
				(gr_arc
					(start -0.529126 1.279127)
					(mid 0.087542 0.105784)
					(end 1.253811 -0.524161)
					(width 0.2)
				)
				(gr_arc
					(start -0.621807 1.279127)
					(mid 0.0309 0.033527)
					(end 1.275473 -0.621136)
					(width 0.2)
				)
				(gr_arc
					(start -0.71437 1.279127)
					(mid -0.037758 -0.026651)
					(end 1.263664 -0.711602)
					(width 0.2)
				)
				(gr_arc
					(start -0.806826 1.279127)
					(mid -0.105837 -0.087395)
					(end 1.253435 -0.802342)
					(width 0.2)
				)
				(gr_arc
					(start -0.899187 1.279127)
					(mid -0.165236 -0.156885)
					(end 1.267475 -0.897258)
					(width 0.2)
				)
				(gr_arc
					(start -0.991463 1.279127)
					(mid -0.228522 -0.222449)
					(end 1.270645 -0.990112)
					(width 0.2)
				)
				(gr_arc
					(start -1.083663 1.279127)
					(mid -0.294507 -0.285313)
					(end 1.266278 -1.081674)
					(width 0.2)
				)
				(gr_line
					(start 1.279127 -0.250195)
					(end 1.279127 -1.083663)
					(width 0.2)
				)
				(gr_line
					(start -0.250195 1.279127)
					(end -1.083663 1.279127)
					(width 0.2)
				)
			)
			(teardrops
				(best_length_ratio 0.2)
				(max_length 1)
				(best_width_ratio 0.9)
				(max_width 2)
				(curved_edges yes)
				(filter_ratio 0.9)
				(enabled yes)
				(allow_two_segments yes)
				(prefer_zone_connections yes)
			)
		)
		(pad "" smd custom
			(at -1.7 1.7)
			(size 0.62 0.62)
			(layers "F.Paste")
			(thermal_bridge_angle 90)
			(options
				(clearance outline)
				(anchor circle)
			)
			(primitives
				(gr_arc
					(start -0.250195 1.279127)
					(mid 0.285453 0.294389)
					(end 1.266786 -0.24747)
					(width 0.2)
				)
				(gr_arc
					(start -0.34334 1.279127)
					(mid 0.218448 0.232561)
					(end 1.259603 -0.339191)
					(width 0.2)
				)
				(gr_arc
					(start -0.436309 1.279127)
					(mid 0.152481 0.169693)
					(end 1.255279 -0.431435)
					(width 0.2)
				)
				(gr_arc
					(start -0.529126 1.279127)
					(mid 0.087542 0.105784)
					(end 1.253811 -0.524161)
					(width 0.2)
				)
				(gr_arc
					(start -0.621807 1.279127)
					(mid 0.0309 0.033527)
					(end 1.275473 -0.621136)
					(width 0.2)
				)
				(gr_arc
					(start -0.71437 1.279127)
					(mid -0.037758 -0.026651)
					(end 1.263664 -0.711602)
					(width 0.2)
				)
				(gr_arc
					(start -0.806826 1.279127)
					(mid -0.105837 -0.087395)
					(end 1.253435 -0.802342)
					(width 0.2)
				)
				(gr_arc
					(start -0.899187 1.279127)
					(mid -0.165236 -0.156885)
					(end 1.267475 -0.897258)
					(width 0.2)
				)
				(gr_arc
					(start -0.991463 1.279127)
					(mid -0.228522 -0.222449)
					(end 1.270645 -0.990112)
					(width 0.2)
				)
				(gr_arc
					(start -1.083663 1.279127)
					(mid -0.294507 -0.285313)
					(end 1.266278 -1.081674)
					(width 0.2)
				)
				(gr_line
					(start 1.279127 -0.250195)
					(end 1.279127 -1.083663)
					(width 0.2)
				)
				(gr_line
					(start -0.250195 1.279127)
					(end -1.083663 1.279127)
					(width 0.2)
				)
			)
			(teardrops
				(best_length_ratio 0.2)
				(max_length 1)
				(best_width_ratio 0.9)
				(max_width 2)
				(curved_edges yes)
				(filter_ratio 0.9)
				(enabled yes)
				(allow_two_segments yes)
				(prefer_zone_connections yes)
			)
		)
		(pad "" smd custom
			(at 1.7 -1.7 180)
			(size 0.62 0.62)
			(layers "F.Paste")
			(thermal_bridge_angle 90)
			(options
				(clearance outline)
				(anchor circle)
			)
			(primitives
				(gr_arc
					(start -0.250195 1.279127)
					(mid 0.285453 0.294389)
					(end 1.266786 -0.24747)
					(width 0.2)
				)
				(gr_arc
					(start -0.34334 1.279127)
					(mid 0.218448 0.232561)
					(end 1.259603 -0.339191)
					(width 0.2)
				)
				(gr_arc
					(start -0.436309 1.279127)
					(mid 0.152481 0.169693)
					(end 1.255279 -0.431435)
					(width 0.2)
				)
				(gr_arc
					(start -0.529126 1.279127)
					(mid 0.087542 0.105784)
					(end 1.253811 -0.524161)
					(width 0.2)
				)
				(gr_arc
					(start -0.621807 1.279127)
					(mid 0.0309 0.033527)
					(end 1.275473 -0.621136)
					(width 0.2)
				)
				(gr_arc
					(start -0.71437 1.279127)
					(mid -0.037758 -0.026651)
					(end 1.263664 -0.711602)
					(width 0.2)
				)
				(gr_arc
					(start -0.806826 1.279127)
					(mid -0.105837 -0.087395)
					(end 1.253435 -0.802342)
					(width 0.2)
				)
				(gr_arc
					(start -0.899187 1.279127)
					(mid -0.165236 -0.156885)
					(end 1.267475 -0.897258)
					(width 0.2)
				)
				(gr_arc
					(start -0.991463 1.279127)
					(mid -0.228522 -0.222449)
					(end 1.270645 -0.990112)
					(width 0.2)
				)
				(gr_arc
					(start -1.083663 1.279127)
					(mid -0.294507 -0.285313)
					(end 1.266278 -1.081674)
					(width 0.2)
				)
				(gr_line
					(start 1.279127 -0.250195)
					(end 1.279127 -1.083663)
					(width 0.2)
				)
				(gr_line
					(start -0.250195 1.279127)
					(end -1.083663 1.279127)
					(width 0.2)
				)
			)
			(teardrops
				(best_length_ratio 0.2)
				(max_length 1)
				(best_width_ratio 0.9)
				(max_width 2)
				(curved_edges yes)
				(filter_ratio 0.9)
				(enabled yes)
				(allow_two_segments yes)
				(prefer_zone_connections yes)
			)
		)
		(pad "" smd custom
			(at 1.7 1.7 90)
			(size 0.62 0.62)
			(layers "F.Paste")
			(thermal_bridge_angle 90)
			(options
				(clearance outline)
				(anchor circle)
			)
			(primitives
				(gr_arc
					(start -0.250195 1.279127)
					(mid 0.285453 0.294389)
					(end 1.266786 -0.24747)
					(width 0.2)
				)
				(gr_arc
					(start -0.34334 1.279127)
					(mid 0.218448 0.232561)
					(end 1.259603 -0.339191)
					(width 0.2)
				)
				(gr_arc
					(start -0.436309 1.279127)
					(mid 0.152481 0.169693)
					(end 1.255279 -0.431435)
					(width 0.2)
				)
				(gr_arc
					(start -0.529126 1.279127)
					(mid 0.087542 0.105784)
					(end 1.253811 -0.524161)
					(width 0.2)
				)
				(gr_arc
					(start -0.621807 1.279127)
					(mid 0.0309 0.033527)
					(end 1.275473 -0.621136)
					(width 0.2)
				)
				(gr_arc
					(start -0.71437 1.279127)
					(mid -0.037758 -0.026651)
					(end 1.263664 -0.711602)
					(width 0.2)
				)
				(gr_arc
					(start -0.806826 1.279127)
					(mid -0.105837 -0.087395)
					(end 1.253435 -0.802342)
					(width 0.2)
				)
				(gr_arc
					(start -0.899187 1.279127)
					(mid -0.165236 -0.156885)
					(end 1.267475 -0.897258)
					(width 0.2)
				)
				(gr_arc
					(start -0.991463 1.279127)
					(mid -0.228522 -0.222449)
					(end 1.270645 -0.990112)
					(width 0.2)
				)
				(gr_arc
					(start -1.083663 1.279127)
					(mid -0.294507 -0.285313)
					(end 1.266278 -1.081674)
					(width 0.2)
				)
				(gr_line
					(start 1.279127 -0.250195)
					(end 1.279127 -1.083663)
					(width 0.2)
				)
				(gr_line
					(start -0.250195 1.279127)
					(end -1.083663 1.279127)
					(width 0.2)
				)
			)
			(teardrops
				(best_length_ratio 0.2)
				(max_length 1)
				(best_width_ratio 0.9)
				(max_width 2)
				(curved_edges yes)
				(filter_ratio 0.9)
				(enabled yes)
				(allow_two_segments yes)
				(prefer_zone_connections yes)
			)
		)
		(pad "1" thru_hole circle
			(at 0 0 270)
			(size 6 6)
			(drill 3.7)
			(layers "*.Cu" "*.Mask")
			(remove_unused_layers no)
			(net 1 "GND")
			(pintype "passive")
			(teardrops
				(best_length_ratio 0.4)
				(max_length 1)
				(best_width_ratio 0.9)
				(max_width 2)
				(curved_edges yes)
				(filter_ratio 0.9)
				(enabled yes)
				(allow_two_segments yes)
				(prefer_zone_connections yes)
			)
		)
	)
	(footprint "antmicro-footprints:R_0402_1005Metric"
		(layer "F.Cu")
		(at 218.43 133.1 -90)
		(descr "Resistor SMD 0402")
		(tags "resistor SMD 0402")
		(property "Reference" "R185"
			(at -1.54 -2.37 90)
			(layer "F.SilkS")
			(effects
				(font
					(size 0.7 0.7)
					(thickness 0.15)
				)
				(justify right bottom)
			)
		)
		(property "Value" "R_1k_0402"
			(at -1.011843 1.772047 90)
			(layer "F.Fab")
			(effects
				(font
					(size 0.7 0.7)
					(thickness 0.15)
				)
				(justify right bottom)
			)
		)
		(property "Datasheet" "https://www.bourns.com/docs/product-datasheets/cr.pdf"
			(at 0 0 270)
			(layer "F.Fab")
			(hide yes)
			(effects
				(font
					(size 1.27 1.27)
					(thickness 0.15)
				)
			)
		)
		(property "Author" "Antmicro"
			(at 85.33 351.53 0)
			(layer "F.Fab")
			(hide yes)
			(effects
				(font
					(size 1 1)
					(thickness 0.15)
				)
			)
		)
		(property "License" "Apache-2.0"
			(at 85.33 351.53 0)
			(layer "F.Fab")
			(hide yes)
			(effects
				(font
					(size 1 1)
					(thickness 0.15)
				)
			)
		)
		(property "MPN" "CR0402-FX-1001GLF"
			(at 85.33 351.53 0)
			(layer "F.Fab")
			(hide yes)
			(effects
				(font
					(size 1 1)
					(thickness 0.15)
				)
			)
		)
		(property "Manufacturer" "Bourns"
			(at 85.33 351.53 0)
			(layer "F.Fab")
			(hide yes)
			(effects
				(font
					(size 1 1)
					(thickness 0.15)
				)
			)
		)
		(property "Public" "False"
			(at 85.33 351.53 0)
			(layer "F.Fab")
			(hide yes)
			(effects
				(font
					(size 1 1)
					(thickness 0.15)
				)
			)
		)
		(property "Tolerance" "1%"
			(at 85.33 351.53 0)
			(layer "F.Fab")
			(hide yes)
			(effects
				(font
					(size 1 1)
					(thickness 0.15)
				)
			)
		)
		(property "Val" "1k"
			(at 85.33 351.53 0)
			(layer "F.Fab")
			(hide yes)
			(effects
				(font
					(size 1 1)
					(thickness 0.15)
				)
			)
		)
		(sheetname "PCIe misc")
		(sheetfile "pcie_misc.kicad_sch")
		(attr smd)
		(fp_rect
			(start -0.925 -0.47)
			(end 0.925 0.47)
			(stroke
				(width 0.05)
				(type default)
			)
			(fill no)
			(layer "F.CrtYd")
		)
		(fp_rect
			(start -0.5 -0.25)
			(end 0.5 0.25)
			(stroke
				(width 0.15)
				(type solid)
			)
			(fill no)
			(layer "F.Fab")
		)
		(pad "1" smd roundrect
			(at -0.48 0 270)
			(size 0.59 0.64)
			(layers "F.Cu" "F.Mask" "F.Paste")
			(roundrect_rratio 0.25)
			(net 605 "Net-(U37-~{OE3})")
			(pintype "passive")
			(teardrops
				(best_length_ratio 0.2)
				(max_length 1)
				(best_width_ratio 0.9)
				(max_width 2)
				(curved_edges yes)
				(filter_ratio 0.9)
				(enabled yes)
				(allow_two_segments yes)
				(prefer_zone_connections yes)
			)
		)
		(pad "2" smd roundrect
			(at 0.48 0 270)
			(size 0.59 0.64)
			(layers "F.Cu" "F.Mask" "F.Paste")
			(roundrect_rratio 0.25)
			(net 1 "GND")
			(pintype "passive")
			(teardrops
				(best_length_ratio 0.2)
				(max_length 1)
				(best_width_ratio 0.9)
				(max_width 2)
				(curved_edges yes)
				(filter_ratio 0.9)
				(enabled yes)
				(allow_two_segments yes)
				(prefer_zone_connections yes)
			)
		)
	)
	(footprint "antmicro-footprints:C_Pol_EIA-D"
		(layer "F.Cu")
		(at 317.324999 119.11 90)
		(property "Reference" "C41"
			(at -5.85 2.325001 90)
			(layer "F.SilkS")
			(effects
				(font
					(size 0.7 0.7)
					(thickness 0.15)
				)
				(justify left bottom)
			)
		)
		(property "Value" "C_Pol_68u_16V_Panasonic-TQC-D"
			(at 0 3.4 90)
			(layer "F.Fab")
			(effects
				(font
					(size 0.7 0.7)
					(thickness 0.15)
				)
				(justify left bottom)
			)
		)
		(property "Datasheet" "https://industrial.panasonic.com/sa/products/pt/aluminum-cap-smd/models/16TQC68MYF"
			(at 0 0 90)
			(layer "F.Fab")
			(hide yes)
			(effects
				(font
					(size 1.27 1.27)
					(thickness 0.15)
				)
			)
		)
		(property "Author" "Antmicro"
			(at 436.434999 -198.214999 0)
			(layer "F.Fab")
			(hide yes)
			(effects
				(font
					(size 1 1)
					(thickness 0.15)
				)
			)
		)
		(property "Dielectric" "template_dielectric"
			(at 436.434999 -198.214999 0)
			(layer "F.Fab")
			(hide yes)
			(effects
				(font
					(size 1 1)
					(thickness 0.15)
				)
			)
		)
		(property "License" "Apache-2.0"
			(at 436.434999 -198.214999 0)
			(layer "F.Fab")
			(hide yes)
			(effects
				(font
					(size 1 1)
					(thickness 0.15)
				)
			)
		)
		(property "MPN" "16TQC68MYF"
			(at 436.434999 -198.214999 0)
			(layer "F.Fab")
			(hide yes)
			(effects
				(font
					(size 1 1)
					(thickness 0.15)
				)
			)
		)
		(property "Manufacturer" "Panasonic"
			(at 436.434999 -198.214999 0)
			(layer "F.Fab")
			(hide yes)
			(effects
				(font
					(size 1 1)
					(thickness 0.15)
				)
			)
		)
		(property "Public" "False"
			(at 436.434999 -198.214999 0)
			(layer "F.Fab")
			(hide yes)
			(effects
				(font
					(size 1 1)
					(thickness 0.15)
				)
			)
		)
		(property "Val" "68u"
			(at 436.434999 -198.214999 0)
			(layer "F.Fab")
			(hide yes)
			(effects
				(font
					(size 1 1)
					(thickness 0.15)
				)
			)
		)
		(property "Voltage" "16V"
			(at 436.434999 -198.214999 0)
			(layer "F.Fab")
			(hide yes)
			(effects
				(font
					(size 1 1)
					(thickness 0.15)
				)
			)
		)
		(sheetname "Power")
		(sheetfile "power.kicad_sch")
		(attr smd)
		(fp_line
			(start 3.6 -2.2)
			(end 3.6 -1.6)
			(stroke
				(width 0.15)
				(type solid)
			)
			(layer "F.SilkS")
		)
		(fp_line
			(start -3.58 -2.2)
			(end 3.6 -2.2)
			(stroke
				(width 0.15)
				(type solid)
			)
			(layer "F.SilkS")
		)
		(fp_line
			(start -4.1 -2.025)
			(end -4.1 -1.625)
			(stroke
				(width 0.12)
				(type solid)
			)
			(layer "F.SilkS")
		)
		(fp_line
			(start -4.3 -1.825)
			(end -3.9 -1.825)
			(stroke
				(width 0.12)
				(type solid)
			)
			(layer "F.SilkS")
		)
		(fp_line
			(start -3.58 -1.6)
			(end -3.58 -2.2)
			(stroke
				(width 0.15)
				(type solid)
			)
			(layer "F.SilkS")
		)
		(fp_line
			(start 3.6 1.6)
			(end 3.6 2.2)
			(stroke
				(width 0.15)
				(type solid)
			)
			(layer "F.SilkS")
		)
		(fp_line
			(start 3.6 2.2)
			(end -3.58 2.2)
			(stroke
				(width 0.15)
				(type solid)
			)
			(layer "F.SilkS")
		)
		(fp_line
			(start -3.58 2.2)
			(end -3.58 1.6)
			(stroke
				(width 0.15)
				(type solid)
			)
			(layer "F.SilkS")
		)
		(fp_line
			(start 3.77 -2.4)
			(end 3.77 -1.51)
			(stroke
				(width 0.05)
				(type solid)
			)
			(layer "F.CrtYd")
		)
		(fp_line
			(start -3.775 -2.4)
			(end 3.77 -2.4)
			(stroke
				(width 0.05)
				(type solid)
			)
			(layer "F.CrtYd")
		)
		(fp_line
			(start -3.775 -2.4)
			(end -3.775 -1.5)
			(stroke
				(width 0.05)
				(type solid)
			)
			(layer "F.CrtYd")
		)
		(fp_line
			(start 4.505 -1.51)
			(end 4.505 1.5)
			(stroke
				(width 0.05)
				(type solid)
			)
			(layer "F.CrtYd")
		)
		(fp_line
			(start 3.77 -1.51)
			(end 4.505 -1.51)
			(stroke
				(width 0.05)
				(type solid)
			)
			(layer "F.CrtYd")
		)
		(fp_line
			(start -3.775 -1.5)
			(end -4.505 -1.5)
			(stroke
				(width 0.05)
				(type solid)
			)
			(layer "F.CrtYd")
		)
		(fp_line
			(start 4.505 1.51)
			(end 3.77 1.51)
			(stroke
				(width 0.05)
				(type solid)
			)
			(layer "F.CrtYd")
		)
		(fp_line
			(start 3.77 1.51)
			(end 3.77 2.4)
			(stroke
				(width 0.05)
				(type solid)
			)
			(layer "F.CrtYd")
		)
		(fp_line
			(start -3.77 1.51)
			(end -4.505 1.51)
			(stroke
				(width 0.05)
				(type solid)
			)
			(layer "F.CrtYd")
		)
		(fp_line
			(start -4.505 1.51)
			(end -4.505 -1.5)
			(stroke
				(width 0.05)
				(type solid)
			)
			(layer "F.CrtYd")
		)
		(fp_line
			(start 3.77 2.4)
			(end -3.77 2.4)
			(stroke
				(width 0.05)
				(type solid)
			)
			(layer "F.CrtYd")
		)
		(fp_line
			(start -3.77 2.4)
			(end -3.77 1.51)
			(stroke
				(width 0.05)
				(type solid)
			)
			(layer "F.CrtYd")
		)
		(fp_rect
			(start -3.65 -2.15)
			(end 3.65 2.15)
			(stroke
				(width 0.15)
				(type solid)
			)
			(fill no)
			(layer "F.Fab")
		)
		(pad "1" smd roundrect
			(at -3.1 0 90)
			(size 2.31 2.52)
			(layers "F.Cu" "F.Mask" "F.Paste")
			(roundrect_rratio 0.1)
			(net 62 "+12V_AON")
			(pintype "passive")
			(teardrops
				(best_length_ratio 0.2)
				(max_length 1)
				(best_width_ratio 0.9)
				(max_width 2)
				(curved_edges yes)
				(filter_ratio 0.9)
				(enabled yes)
				(allow_two_segments yes)
				(prefer_zone_connections yes)
			)
		)
		(pad "2" smd roundrect
			(at 3.1 0 90)
			(size 2.31 2.52)
			(layers "F.Cu" "F.Mask" "F.Paste")
			(roundrect_rratio 0.1)
			(net 1 "GND")
			(pintype "passive")
			(teardrops
				(best_length_ratio 0.2)
				(max_length 1)
				(best_width_ratio 0.9)
				(max_width 2)
				(curved_edges yes)
				(filter_ratio 0.9)
				(enabled yes)
				(allow_two_segments yes)
				(prefer_zone_connections yes)
			)
		)
	)
)
